# T6G (Grand Teton) — schematic netlist excerpt (pin names and nets, part order shuffled) for the footprints in the layout excerpt that follows; sources: Cadence DE-HDL packaged netlist, KiCad conversion of 04192023_DAF0TMB3IC0_F0TG_MB_C_brd_V02_OCP.brd

PR334  Q_RES  1K 1% CHIP  pkg 0402LF  page 198 : A = PVDDCR_SOC_P0 ; B = GND
R6036  Q_RES  2K 1% EMPTY  pkg 0402LF  page 151 : A = SMB_1_PLD_3V3AUX_SCL ; B = P3V3_AUX

(kicad_pcb
	(version 20260206)
	(generator "pcbnew")
	(generator_version "10.0")
	(general
		(thickness 1.6)
		(legacy_teardrops no)
	)
	(paper "A4")
	(title_block
		(title "04192023_DAF0TMB3IC0_F0TG_MB_C_brd_V02_OCP.brd")
		(comment 1 "Grand Teton / footprints 8087-8088 of 8354")
	)
	(layers
		(0 "F.Cu" signal "TOP")
		(4 "In1.Cu" signal "GND")
		(6 "In2.Cu" signal "IN1")
		(8 "In3.Cu" signal "GND1")
		(10 "In4.Cu" signal "IN2")
		(12 "In5.Cu" signal "GND2")
		(14 "In6.Cu" signal "IN3")
		(16 "In7.Cu" signal "GND3")
		(18 "In8.Cu" signal "VCC")
		(20 "In9.Cu" signal "VCC1")
		(22 "In10.Cu" signal "GND4")
		(24 "In11.Cu" signal "IN4")
		(26 "In12.Cu" signal "GND5")
		(28 "In13.Cu" signal "IN5")
		(30 "In14.Cu" signal "GND6")
		(32 "In15.Cu" signal "IN6")
		(34 "In16.Cu" signal "GND7")
		(2 "B.Cu" signal "BOTTOM")
		(9 "F.Adhes" user "F.Adhesive")
		(11 "B.Adhes" user "B.Adhesive")
		(13 "F.Paste" user "Package Geometry/Pastemask Top")
		(15 "B.Paste" user "Package Geometry/Pastemask Bottom")
		(5 "F.SilkS" user "Ref Des/Silkscreen Top")
		(7 "B.SilkS" user "Ref Des/Silkscreen Bottom")
		(1 "F.Mask" user "Board Geometry/Soldermask Top")
		(3 "B.Mask" user "Board Geometry/Soldermask Bottom")
		(17 "Dwgs.User" user "User.Drawings")
		(19 "Cmts.User" user "User.Comments")
		(21 "Eco1.User" user "User.Eco1")
		(23 "Eco2.User" user "User.Eco2")
		(25 "Edge.Cuts" user "Board Geometry/Outline")
		(27 "Margin" user)
		(31 "F.CrtYd" user "Package Geometry/Place Bound Top")
		(29 "B.CrtYd" user "Package Geometry/Place Bound Bottom")
		(35 "F.Fab" user "Ref Des/Assembly Top")
		(33 "B.Fab" user "Ref Des/Assembly Bottom")
	)
	(footprint ""
		(layer "B.Cu")
		(at 420.407338 -172.290232 90)
		(property "Reference" "PR334"
			(at 0 0 90)
			(layer "B.SilkS")
			(hide yes)
			(effects
				(font
					(size 1.27 1.27)
				)
				(justify mirror)
			)
		)
		(property "Value" ""
			(at 0 0 90)
			(layer "B.Fab")
			(effects
				(font
					(size 1.27 1.27)
				)
				(justify mirror)
			)
		)
		(duplicate_pad_numbers_are_jumpers no)
		(fp_line
			(start 0.7874 -0.4064)
			(end -0.7874 -0.4064)
			(stroke
				(width 0.1524)
				(type default)
			)
			(layer "B.SilkS")
		)
		(fp_line
			(start -0.7874 -0.4064)
			(end -0.7874 0.4064)
			(stroke
				(width 0.1524)
				(type default)
			)
			(layer "B.SilkS")
		)
		(fp_line
			(start 0.7874 0.4064)
			(end 0.7874 -0.4064)
			(stroke
				(width 0.1524)
				(type default)
			)
			(layer "B.SilkS")
		)
		(fp_line
			(start -0.7874 0.4064)
			(end 0.7874 0.4064)
			(stroke
				(width 0.1524)
				(type default)
			)
			(layer "B.SilkS")
		)
		(fp_line
			(start 0.67945 -0.305054)
			(end 0.12065 -0.305054)
			(stroke
				(width 0.1)
				(type default)
			)
			(layer "B.Fab")
		)
		(fp_line
			(start 0.12065 -0.305054)
			(end 0.12065 -0.2794)
			(stroke
				(width 0.1)
				(type default)
			)
			(layer "B.Fab")
		)
		(fp_line
			(start -0.12065 -0.3048)
			(end -0.67945 -0.3048)
			(stroke
				(width 0.1)
				(type default)
			)
			(layer "B.Fab")
		)
		(fp_line
			(start -0.67945 -0.3048)
			(end -0.67945 0.3048)
			(stroke
				(width 0.1)
				(type default)
			)
			(layer "B.Fab")
		)
		(fp_line
			(start 0.12065 -0.2794)
			(end -0.12065 -0.2794)
			(stroke
				(width 0.1)
				(type default)
			)
			(layer "B.Fab")
		)
		(fp_line
			(start -0.12065 -0.2794)
			(end -0.12065 -0.3048)
			(stroke
				(width 0.1)
				(type default)
			)
			(layer "B.Fab")
		)
		(fp_line
			(start 0.12065 0.2794)
			(end 0.12065 0.3048)
			(stroke
				(width 0.1)
				(type default)
			)
			(layer "B.Fab")
		)
		(fp_line
			(start -0.120396 0.2794)
			(end 0.12065 0.2794)
			(stroke
				(width 0.1)
				(type default)
			)
			(layer "B.Fab")
		)
		(fp_line
			(start 0.67945 0.3048)
			(end 0.67945 -0.305054)
			(stroke
				(width 0.1)
				(type default)
			)
			(layer "B.Fab")
		)
		(fp_line
			(start 0.12065 0.3048)
			(end 0.67945 0.3048)
			(stroke
				(width 0.1)
				(type default)
			)
			(layer "B.Fab")
		)
		(fp_line
			(start -0.120396 0.3048)
			(end -0.120396 0.2794)
			(stroke
				(width 0.1)
				(type default)
			)
			(layer "B.Fab")
		)
		(fp_line
			(start -0.67945 0.3048)
			(end -0.120396 0.3048)
			(stroke
				(width 0.1)
				(type default)
			)
			(layer "B.Fab")
		)
		(pad "1" smd circle
			(at 0.40005 0 270)
			(size 0 0)
			(layers "B.Cu" "B.Mask" "B.Paste")
			(net "PVDDCR_SOC_P0")
		)
		(pad "2" smd circle
			(at -0.40005 0 270)
			(size 0 0)
			(layers "B.Cu" "B.Mask" "B.Paste")
			(net "GND")
		)
	)
	(footprint ""
		(layer "B.Cu")
		(at 162.73018 -20.056094 90)
		(property "Reference" "R6036"
			(at 0 0 90)
			(layer "B.SilkS")
			(hide yes)
			(effects
				(font
					(size 1.27 1.27)
				)
				(justify mirror)
			)
		)
		(property "Value" ""
			(at 0 0 90)
			(layer "B.Fab")
			(effects
				(font
					(size 1.27 1.27)
				)
				(justify mirror)
			)
		)
		(duplicate_pad_numbers_are_jumpers no)
		(fp_line
			(start 0.7874 -0.4064)
			(end -0.7874 -0.4064)
			(stroke
				(width 0.1524)
				(type default)
			)
			(layer "B.SilkS")
		)
		(fp_line
			(start -0.7874 -0.4064)
			(end -0.7874 0.4064)
			(stroke
				(width 0.1524)
				(type default)
			)
			(layer "B.SilkS")
		)
		(fp_line
			(start 0.7874 0.4064)
			(end 0.7874 -0.4064)
			(stroke
				(width 0.1524)
				(type default)
			)
			(layer "B.SilkS")
		)
		(fp_line
			(start -0.7874 0.4064)
			(end 0.7874 0.4064)
			(stroke
				(width 0.1524)
				(type default)
			)
			(layer "B.SilkS")
		)
		(fp_line
			(start 0.67945 -0.305054)
			(end 0.12065 -0.305054)
			(stroke
				(width 0.1)
				(type default)
			)
			(layer "B.Fab")
		)
		(fp_line
			(start 0.12065 -0.305054)
			(end 0.12065 -0.2794)
			(stroke
				(width 0.1)
				(type default)
			)
			(layer "B.Fab")
		)
		(fp_line
			(start -0.12065 -0.3048)
			(end -0.67945 -0.3048)
			(stroke
				(width 0.1)
				(type default)
			)
			(layer "B.Fab")
		)
		(fp_line
			(start -0.67945 -0.3048)
			(end -0.67945 0.3048)
			(stroke
				(width 0.1)
				(type default)
			)
			(layer "B.Fab")
		)
		(fp_line
			(start 0.12065 -0.2794)
			(end -0.12065 -0.2794)
			(stroke
				(width 0.1)
				(type default)
			)
			(layer "B.Fab")
		)
		(fp_line
			(start -0.12065 -0.2794)
			(end -0.12065 -0.3048)
			(stroke
				(width 0.1)
				(type default)
			)
			(layer "B.Fab")
		)
		(fp_line
			(start 0.12065 0.2794)
			(end 0.12065 0.3048)
			(stroke
				(width 0.1)
				(type default)
			)
			(layer "B.Fab")
		)
		(fp_line
			(start -0.120396 0.2794)
			(end 0.12065 0.2794)
			(stroke
				(width 0.1)
				(type default)
			)
			(layer "B.Fab")
		)
		(fp_line
			(start 0.67945 0.3048)
			(end 0.67945 -0.305054)
			(stroke
				(width 0.1)
				(type default)
			)
			(layer "B.Fab")
		)
		(fp_line
			(start 0.12065 0.3048)
			(end 0.67945 0.3048)
			(stroke
				(width 0.1)
				(type default)
			)
			(layer "B.Fab")
		)
		(fp_line
			(start -0.120396 0.3048)
			(end -0.120396 0.2794)
			(stroke
				(width 0.1)
				(type default)
			)
			(layer "B.Fab")
		)
		(fp_line
			(start -0.67945 0.3048)
			(end -0.120396 0.3048)
			(stroke
				(width 0.1)
				(type default)
			)
			(layer "B.Fab")
		)
		(pad "1" smd circle
			(at 0.40005 0 270)
			(size 0 0)
			(layers "B.Cu" "B.Mask" "B.Paste")
			(net "SMB_1_PLD_3V3AUX_SCL")
		)
		(pad "2" smd circle
			(at -0.40005 0 270)
			(size 0 0)
			(layers "B.Cu" "B.Mask" "B.Paste")
			(net "P3V3_AUX")
		)
	)
)
